# T6G (Grand Teton) — schematic netlist excerpt (pin names and nets, part order shuffled) for the footprints in the layout excerpt that follows; sources: Cadence DE-HDL packaged netlist, KiCad conversion of 04192023_DAF0TMB3IC0_F0TG_MB_C_brd_V02_OCP.brd

U206  LT6700CS61TRPBF  LT6700CS6-1#TRPBF EMPTY  pkg TSOT23-6_0-95_2-9X1-625  page 268
  OUTA  = FM_UV_ADR_TRIGGER_N
  GND  = GND
  \ina+\  = A_P12V_STBY_ADR_TRIGGER
  \inb-\  = A_P12V_STBY_FP_TRIGGER
  VS  = U206_VS
  OUTB  = A_P12V_STBY_FPH_GATE

R1838  Q_RES_4P_12  0.001 1% CHIP  pkg R2512_4P_H41  page 259
  \1\  = P12V_AUX
  \2\  = P12V_MEM_CPU0
  \3\  = TP_P12V_AUX_CPU0_DIMM_ISEN_P
  \4\  = TP_P12V_AUX_CPU0_DIMM_ISEN_N

(kicad_pcb
	(version 20260206)
	(generator "pcbnew")
	(generator_version "10.0")
	(general
		(thickness 1.6)
		(legacy_teardrops no)
	)
	(paper "A4")
	(title_block
		(title "04192023_DAF0TMB3IC0_F0TG_MB_C_brd_V02_OCP.brd")
		(comment 1 "Grand Teton / footprints 2734-2735 of 8354")
	)
	(layers
		(0 "F.Cu" signal "TOP")
		(4 "In1.Cu" signal "GND")
		(6 "In2.Cu" signal "IN1")
		(8 "In3.Cu" signal "GND1")
		(10 "In4.Cu" signal "IN2")
		(12 "In5.Cu" signal "GND2")
		(14 "In6.Cu" signal "IN3")
		(16 "In7.Cu" signal "GND3")
		(18 "In8.Cu" signal "VCC")
		(20 "In9.Cu" signal "VCC1")
		(22 "In10.Cu" signal "GND4")
		(24 "In11.Cu" signal "IN4")
		(26 "In12.Cu" signal "GND5")
		(28 "In13.Cu" signal "IN5")
		(30 "In14.Cu" signal "GND6")
		(32 "In15.Cu" signal "IN6")
		(34 "In16.Cu" signal "GND7")
		(2 "B.Cu" signal "BOTTOM")
		(9 "F.Adhes" user "F.Adhesive")
		(11 "B.Adhes" user "B.Adhesive")
		(13 "F.Paste" user "Package Geometry/Pastemask Top")
		(15 "B.Paste" user "Package Geometry/Pastemask Bottom")
		(5 "F.SilkS" user "Ref Des/Silkscreen Top")
		(7 "B.SilkS" user "Ref Des/Silkscreen Bottom")
		(1 "F.Mask" user "Board Geometry/Soldermask Top")
		(3 "B.Mask" user "Board Geometry/Soldermask Bottom")
		(17 "Dwgs.User" user "User.Drawings")
		(19 "Cmts.User" user "User.Comments")
		(21 "Eco1.User" user "User.Eco1")
		(23 "Eco2.User" user "User.Eco2")
		(25 "Edge.Cuts" user "Board Geometry/Outline")
		(27 "Margin" user)
		(31 "F.CrtYd" user "Package Geometry/Place Bound Top")
		(29 "B.CrtYd" user "Package Geometry/Place Bound Bottom")
		(35 "F.Fab" user "Ref Des/Assembly Top")
		(33 "B.Fab" user "Ref Des/Assembly Bottom")
	)
	(footprint ""
		(layer "F.Cu")
		(at 450.857366 -180.106066 180)
		(property "Reference" "R1838"
			(at -4.945634 -3.856736 0)
			(unlocked yes)
			(layer "F.SilkS")
			(effects
				(font
					(size 0.7874 0.5842)
					(thickness 0.1524)
				)
				(justify left)
			)
		)
		(property "Value" ""
			(at 0 0 180)
			(layer "F.Fab")
			(effects
				(font
					(size 1.27 1.27)
				)
			)
		)
		(duplicate_pad_numbers_are_jumpers no)
		(fp_line
			(start 4.0386 1.7526)
			(end -4.0386 1.7526)
			(stroke
				(width 0.1524)
				(type default)
			)
			(layer "F.SilkS")
		)
		(fp_line
			(start 4.0386 -1.7526)
			(end 4.0386 1.7526)
			(stroke
				(width 0.1524)
				(type default)
			)
			(layer "F.SilkS")
		)
		(fp_line
			(start -4.0386 1.7526)
			(end -4.0386 -1.7526)
			(stroke
				(width 0.1524)
				(type default)
			)
			(layer "F.SilkS")
		)
		(fp_line
			(start -4.0386 -1.7526)
			(end 4.0386 -1.7526)
			(stroke
				(width 0.1524)
				(type default)
			)
			(layer "F.SilkS")
		)
		(fp_line
			(start 4.0386 1.7526)
			(end -4.0386 1.7526)
			(stroke
				(width 0.1)
				(type default)
			)
			(layer "F.Fab")
		)
		(fp_line
			(start 4.0386 -1.7526)
			(end 4.0386 1.7526)
			(stroke
				(width 0.1)
				(type default)
			)
			(layer "F.Fab")
		)
		(fp_line
			(start -4.0386 1.7526)
			(end -4.0386 -1.7526)
			(stroke
				(width 0.1)
				(type default)
			)
			(layer "F.Fab")
		)
		(fp_line
			(start -4.0386 -1.7526)
			(end 4.0386 -1.7526)
			(stroke
				(width 0.1)
				(type default)
			)
			(layer "F.Fab")
		)
		(pad "1" smd circle
			(at -3.700018 0 90)
			(size 0 0)
			(layers "F.Cu" "F.Mask" "F.Paste")
			(net "P12V_AUX")
		)
		(pad "2" smd circle
			(at 3.700018 0 270)
			(size 0 0)
			(layers "F.Cu" "F.Mask" "F.Paste")
			(net "P12V_MEM_CPU0")
		)
		(pad "3" smd rect
			(at -2.70002 0 270)
			(size 0.4064 1.1176)
			(layers "F.Cu" "F.Mask" "F.Paste")
			(net "TP_P12V_AUX_CPU0_DIMM_ISEN_P")
		)
		(pad "4" smd rect
			(at 2.70002 0 270)
			(size 0.4064 1.1176)
			(layers "F.Cu" "F.Mask" "F.Paste")
			(net "TP_P12V_AUX_CPU0_DIMM_ISEN_N")
		)
	)
	(footprint ""
		(layer "F.Cu")
		(at 155.459938 -118.132352 180)
		(property "Reference" "U206"
			(at -2.499106 -1.948434 0)
			(unlocked yes)
			(layer "F.SilkS")
			(effects
				(font
					(size 0.7874 0.5842)
					(thickness 0.1524)
				)
				(justify left)
			)
		)
		(property "Value" ""
			(at 0 0 180)
			(layer "F.Fab")
			(effects
				(font
					(size 1.27 1.27)
				)
			)
		)
		(duplicate_pad_numbers_are_jumpers no)
		(fp_line
			(start 2.046478 1.450086)
			(end 2.046478 -1.450086)
			(stroke
				(width 0.1524)
				(type default)
			)
			(layer "F.SilkS")
		)
		(fp_line
			(start 2.046478 -1.450086)
			(end 0.484886 -1.450086)
			(stroke
				(width 0.1524)
				(type default)
			)
			(layer "F.SilkS")
		)
		(fp_line
			(start 0.484886 -1.450086)
			(end 0 -0.762)
			(stroke
				(width 0.1524)
				(type default)
			)
			(layer "F.SilkS")
		)
		(fp_line
			(start 0 -0.762)
			(end -0.484886 -1.450086)
			(stroke
				(width 0.1524)
				(type default)
			)
			(layer "F.SilkS")
		)
		(fp_line
			(start -0.484886 -1.450086)
			(end -2.046478 -1.450086)
			(stroke
				(width 0.1524)
				(type default)
			)
			(layer "F.SilkS")
		)
		(fp_line
			(start -2.046478 1.450086)
			(end 2.046478 1.450086)
			(stroke
				(width 0.1524)
				(type default)
			)
			(layer "F.SilkS")
		)
		(fp_line
			(start -2.046478 -1.450086)
			(end -2.046478 1.450086)
			(stroke
				(width 0.1524)
				(type default)
			)
			(layer "F.SilkS")
		)
		(fp_poly
			(pts
				(xy -3.021076 -0.973836) (xy -4.037076 -0.465836) (xy -4.037076 -1.481836)
			)
			(stroke
				(width 0)
				(type default)
			)
			(fill yes)
			(layer "F.SilkS")
		)
		(fp_line
			(start 0.87503 1.450086)
			(end 0.87503 -1.450086)
			(stroke
				(width 0.1)
				(type default)
			)
			(layer "F.Fab")
		)
		(fp_line
			(start 0.87503 -1.450086)
			(end -0.87503 -1.450086)
			(stroke
				(width 0.1)
				(type default)
			)
			(layer "F.Fab")
		)
		(fp_line
			(start -0.87503 1.450086)
			(end 0.87503 1.450086)
			(stroke
				(width 0.1)
				(type default)
			)
			(layer "F.Fab")
		)
		(fp_line
			(start -0.87503 -1.450086)
			(end -0.87503 1.450086)
			(stroke
				(width 0.1)
				(type default)
			)
			(layer "F.Fab")
		)
		(fp_poly
			(pts
				(xy -3.2512 -0.44196) (xy -3.2512 -1.45796) (xy -2.2352 -0.94996)
			)
			(stroke
				(width 0)
				(type default)
			)
			(fill yes)
			(layer "F.Fab")
		)
		(pad "1" smd rect
			(at -1.309878 -0.94996 270)
			(size 0.635 1.2192)
			(layers "F.Cu" "F.Mask" "F.Paste")
			(net "FM_UV_ADR_TRIGGER_N")
		)
		(pad "2" smd rect
			(at -1.309878 0 270)
			(size 0.635 1.2192)
			(layers "F.Cu" "F.Mask" "F.Paste")
			(net "GND")
		)
		(pad "3" smd rect
			(at -1.309878 0.94996 270)
			(size 0.635 1.2192)
			(layers "F.Cu" "F.Mask" "F.Paste")
			(net "A_P12V_STBY_ADR_TRIGGER")
		)
		(pad "4" smd rect
			(at 1.309878 0.94996 270)
			(size 0.635 1.2192)
			(layers "F.Cu" "F.Mask" "F.Paste")
			(net "A_P12V_STBY_FP_TRIGGER")
		)
		(pad "5" smd rect
			(at 1.309878 0 270)
			(size 0.635 1.2192)
			(layers "F.Cu" "F.Mask" "F.Paste")
			(net "U206_VS")
		)
		(pad "6" smd rect
			(at 1.309878 -0.94996 270)
			(size 0.635 1.2192)
			(layers "F.Cu" "F.Mask" "F.Paste")
			(net "A_P12V_STBY_FPH_GATE")
		)
	)
)
